# Stackup_grand teton_MB_18L_2p413mm_EM-890K_VL411_Rev0p6_20230202.xls — Vendor Stackup (pcb-stackup)
| STACKUP |  |  |  | Target Z (ohms) - MicroStrip |  |  |  |  |  |  |  | 40 |  |  | 45 |  |  | 50 |  |  | Breakout | 85 |  |  |  |  | 93 |  |  |  |  | 100 |  |  |  |  |  |  |  |  |  | Breakout |  |  |  |  |
|  |  |  |  | Target Z (ohms) - StripLine |  |  |  |  |  |  |  | 40 |  |  | 45 |  |  | 50 |  |  |  | 85 |  |  |  |  | 93 |  |  |  |  | 100 |  |  |  |  | 93(Breakout region) |  |  |  |  |  |  |  |  |  |
|  |  |  |  | Z tolerance |  |  |  |  |  |  |  | 0.1 |  |  | 0.1 |  |  | 0.1 |  |  |  | 0.1 |  |  |  |  | 0.1 |  |  |  |  | 0.1 |  |  |  |  | 0.1 |  |  |  |  |  |  |  |  |  |
|  |  |  |  | Z Type |  |  |  |  |  |  |  | Single |  |  | Single |  |  | Single |  |  | Single | Differential |  |  |  |  | Differential |  |  |  |  | Differential |  |  |  |  | Differential |  |  |  |  | Differential |  |  |  |  |
| Layer# | Material | Description |  | Copper Weight (oz) | Thickness (mil) | Tolerance (mil) | Glass Fabric | Er | Vendor Thickness (mil) | Vendor Glass Fabric | Vendor Er | Width | Vendor Width | Vendor Impedance | Width | Vendor Width | Vendor Impedance | Width | Vendor Width | Vendor Impedance | Width | Width | Space | Vendor Width | Vendor Space | Vendor Impedance | Width | Space | Vendor Width | Vendor Space | Vendor Impedance | Width | Space | Vendor Width | Vendor Space | Vendor Impedance | Width | Space | Vendor Width | Vendor Space | Vendor Impedance | Width | Space | Vendor Width | Vendor Space | Vendor Impedance |
|  |  |  | Soldermask |  | 0.6 |  |  | 3.8 |  |  |  |  |  |  |  |  |  |  |  |  |  |  |  |  |  |  |  |  |  |  |  |  |  |  |  |  |  |  |  |  |  |  |  |  |  |  |
| 1 |  |  | TOP | 0.5+plating | 1.95 |  |  |  |  |  |  | 7.9 |  |  | 6.3 |  |  | 5.1 |  |  | 3.5 | 5.2 | 5 |  |  |  | 5 | 8.5 |  |  |  | 4.4 | 9.5 |  |  |  |  |  |  |  |  | 3.5 | 4 |  |  |  |
|  | EM-890K |  | PP |  | 2.7 | ±0.709 | 1078x1 | 2.92 |  |  |  |  |  |  |  |  |  |  |  |  |  |  |  |  |  |  |  |  |  |  |  |  |  |  |  |  |  |  |  |  |  |  |  |  |  |  |
| 2 |  |  | GND | 0.5 (VL411) | 0.65 |  |  |  |  |  |  |  |  |  |  |  |  |  |  |  |  |  |  |  |  |  |  |  |  |  |  |  |  |  |  |  |  |  |  |  |  |  |  |  |  |  |
|  | EM-890K |  | CORE |  | 4 | ±0.709 | 1078x1 | 2.93 |  |  |  |  |  |  |  |  |  |  |  |  |  |  |  |  |  |  |  |  |  |  |  |  |  |  |  |  |  |  |  |  |  |  |  |  |  |  |
| 3 |  |  | IN1 | 1 (VL411) | 1.3 |  |  |  |  |  |  | 7.2 |  |  | 6.1 |  |  | 5 |  |  | 3.5 | 5.8 | 5 |  |  |  | 5.5 | 9.1 |  |  |  | 4.9 | 11.8 |  |  |  | 4 | 3 |  |  |  | 3.5 | 4 |  |  |  |
|  | EM-890K |  | PP |  | 5 | ±0.984 | 1078x2 | 2.94 |  |  |  |  |  |  |  |  |  |  |  |  |  |  |  |  |  |  |  |  |  |  |  |  |  |  |  |  |  |  |  |  |  |  |  |  |  |  |
| 4 |  |  | GND1 | 0.5 (VL411) | 0.65 |  |  |  |  |  |  |  |  |  |  |  |  |  |  |  |  |  |  |  |  |  |  |  |  |  |  |  |  |  |  |  |  |  |  |  |  |  |  |  |  |  |
|  | EM-890K |  | CORE |  | 4 | ±0.709 | 1078x1 | 2.93 |  |  |  |  |  |  |  |  |  |  |  |  |  |  |  |  |  |  |  |  |  |  |  |  |  |  |  |  |  |  |  |  |  |  |  |  |  |  |
| 5 |  |  | IN2 | 1 (VL411) | 1.3 |  |  |  |  |  |  | 7.2 |  |  | 6.1 |  |  | 5 |  |  | 3.5 | 5.8 | 5 |  |  |  | 5.5 | 9.1 |  |  |  | 4.9 | 11.8 |  |  |  | 4 | 3 |  |  |  | 3.5 | 4 |  |  |  |
|  | EM-890K |  | PP |  | 5 | ±0.984 | 1078x2 | 2.94 |  |  |  |  |  |  |  |  |  |  |  |  |  |  |  |  |  |  |  |  |  |  |  |  |  |  |  |  |  |  |  |  |  |  |  |  |  |  |
| 6 |  |  | GND2 | 0.5 (VL411) | 0.65 |  |  |  |  |  |  |  |  |  |  |  |  |  |  |  |  |  |  |  |  |  |  |  |  |  |  |  |  |  |  |  |  |  |  |  |  |  |  |  |  |  |
|  | EM-890K |  | CORE |  | 4 | ±0.709 | 1078x1 | 2.93 |  |  |  |  |  |  |  |  |  |  |  |  |  |  |  |  |  |  |  |  |  |  |  |  |  |  |  |  |  |  |  |  |  |  |  |  |  |  |
| 7 |  |  | IN3 | 1 (VL411) | 1.3 |  |  |  |  |  |  | 7.2 |  |  | 6.1 |  |  | 5 |  |  | 3.5 | 5.8 | 5 |  |  |  | 5.5 | 9.1 |  |  |  | 4.9 | 11.8 |  |  |  | 4 | 3 |  |  |  | 3.5 | 4 |  |  |  |
|  | EM-890K |  | PP |  | 5 | ±0.984 | 1078x2 | 2.94 |  |  |  |  |  |  |  |  |  |  |  |  |  |  |  |  |  |  |  |  |  |  |  |  |  |  |  |  |  |  |  |  |  |  |  |  |  |  |
| 8 |  |  | GND3 | 1 (VL411) | 1.3 |  |  |  |  |  |  |  |  |  |  |  |  |  |  |  |  |  |  |  |  |  |  |  |  |  |  |  |  |  |  |  |  |  |  |  |  |  |  |  |  |  |
|  | EM-890K |  | CORE |  | 3.5 | ±0.709 | 1078x1 | 2.93 |  |  |  |  |  |  |  |  |  |  |  |  |  |  |  |  |  |  |  |  |  |  |  |  |  |  |  |  |  |  |  |  |  |  |  |  |  |  |
| 9 |  |  | VCC | 2 (RTF) | 2.6 |  |  |  |  |  |  |  |  |  |  |  |  |  |  |  |  |  |  |  |  |  |  |  |  |  |  |  |  |  |  |  |  |  |  |  |  |  |  |  |  |  |
|  | EM-890K |  | PP |  | 4 | ±0.709 | 1080x2 | 2.93 |  |  |  |  |  |  |  |  |  |  |  |  |  |  |  |  |  |  |  |  |  |  |  |  |  |  |  |  |  |  |  |  |  |  |  |  |  |  |
| 10 |  |  | VCC1 | 2 (RTF) | 2.6 |  |  |  |  |  |  |  |  |  |  |  |  |  |  |  |  |  |  |  |  |  |  |  |  |  |  |  |  |  |  |  |  |  |  |  |  |  |  |  |  |  |
|  | EM-890K |  | CORE |  | 3.5 | ±0.709 | 1078x1 | 2.93 |  |  |  |  |  |  |  |  |  |  |  |  |  |  |  |  |  |  |  |  |  |  |  |  |  |  |  |  |  |  |  |  |  |  |  |  |  |  |
| 11 |  |  | GND4 | 1 (VL411) | 1.3 |  |  |  |  |  |  |  |  |  |  |  |  |  |  |  |  |  |  |  |  |  |  |  |  |  |  |  |  |  |  |  |  |  |  |  |  |  |  |  |  |  |
|  | EM-890K |  | PP |  | 5 | ±0.984 | 1078x2 | 2.94 |  |  |  |  |  |  |  |  |  |  |  |  |  |  |  |  |  |  |  |  |  |  |  |  |  |  |  |  |  |  |  |  |  |  |  |  |  |  |
| 12 |  |  | IN4 | 1 (VL411) | 1.3 |  |  |  |  |  |  | 7.2 |  |  | 6.1 |  |  | 5 |  |  | 3.5 | 5.8 | 5 |  |  |  | 5.5 | 9.1 |  |  |  | 4.9 | 11.8 |  |  |  | 4 | 3 |  |  |  | 3.5 | 4 |  |  |  |
|  | EM-890K |  | CORE |  | 4 | ±0.709 | 1078x1 | 2.93 |  |  |  |  |  |  |  |  |  |  |  |  |  |  |  |  |  |  |  |  |  |  |  |  |  |  |  |  |  |  |  |  |  |  |  |  |  |  |
| 13 |  |  | GND5 | 0.5 (VL411) | 0.65 |  |  |  |  |  |  |  |  |  |  |  |  |  |  |  |  |  |  |  |  |  |  |  |  |  |  |  |  |  |  |  |  |  |  |  |  |  |  |  |  |  |
|  | EM-890K |  | PP |  | 5 | ±0.984 | 1078x2 | 2.94 |  |  |  |  |  |  |  |  |  |  |  |  |  |  |  |  |  |  |  |  |  |  |  |  |  |  |  |  |  |  |  |  |  |  |  |  |  |  |
| 14 |  |  | IN5 | 1 (VL411) | 1.3 |  |  |  |  |  |  | 7.2 |  |  | 6.1 |  |  | 5 |  |  | 3.5 | 5.8 | 5 |  |  |  | 5.5 | 9.1 |  |  |  | 4.9 | 11.8 |  |  |  | 4 | 3 |  |  |  | 3.5 | 4 |  |  |  |
|  | EM-890K |  | CORE |  | 4 | ±0.709 | 1078x1 | 2.93 |  |  |  |  |  |  |  |  |  |  |  |  |  |  |  |  |  |  |  |  |  |  |  |  |  |  |  |  |  |  |  |  |  |  |  |  |  |  |
| 15 |  |  | GND6 | 0.5 (VL411) | 0.65 |  |  |  |  |  |  |  |  |  |  |  |  |  |  |  |  |  |  |  |  |  |  |  |  |  |  |  |  |  |  |  |  |  |  |  |  |  |  |  |  |  |
|  | EM-890K |  | PP |  | 5 | ±0.984 | 1078x2 | 2.94 |  |  |  |  |  |  |  |  |  |  |  |  |  |  |  |  |  |  |  |  |  |  |  |  |  |  |  |  |  |  |  |  |  |  |  |  |  |  |
| 16 |  |  | IN6 | 1 (VL411) | 1.3 |  |  |  |  |  |  | 7.2 |  |  | 6.1 |  |  | 5 |  |  | 3.5 | 5.8 | 5 |  |  |  | 5.5 | 9.1 |  |  |  | 4.9 | 11.8 |  |  |  | 4 | 3 |  |  |  | 3.5 | 4 |  |  |  |
|  | EM-890K |  | CORE |  | 4 | ±0.709 | 1078x1 | 2.93 |  |  |  |  |  |  |  |  |  |  |  |  |  |  |  |  |  |  |  |  |  |  |  |  |  |  |  |  |  |  |  |  |  |  |  |  |  |  |
| 17 |  |  | GND7 | 0.5 (VL411) | 0.65 |  |  |  |  |  |  |  |  |  |  |  |  |  |  |  |  |  |  |  |  |  |  |  |  |  |  |  |  |  |  |  |  |  |  |  |  |  |  |  |  |  |
|  | EM-890K |  | PP |  | 2.7 | ±0.709 | 1078x1 | 2.92 |  |  |  |  |  |  |  |  |  |  |  |  |  |  |  |  |  |  |  |  |  |  |  |  |  |  |  |  |  |  |  |  |  |  |  |  |  |  |
| 18 |  |  | BOTTOM | 0.5+plating | 1.95 |  |  |  |  |  |  | 7.9 |  |  | 6.3 |  |  | 5.1 |  |  | 3.5 | 5.2 | 5 |  |  |  | 5 | 8.5 |  |  |  | 4.4 | 9.5 |  |  |  |  |  |  |  |  | 3.5 | 4 |  |  |  |
|  |  |  | Soldermask |  | 0.6 |  |  | 3.8 |  |  |  |  |  |  |  |  |  |  |  |  |  |  |  |  |  |  |  |  |  |  |  |  |  |  |  |  |  |  |  |  |  |  |  |  |  |  |
|  |  |  |  | Total | 95 | ±10% |  |  | 0 |  |  |  |  |  |  |  |  |  |  |  |  |  |  |  |  |  |  |  |  |  |  |  |  |  |  |  |  |  |  |  |  |  |  |  |  |  |
